(kicad_pcb
	(version 20241229)
	(generator "pcbnew")
	(generator_version "9.0")
	(general
		(thickness 1.63)
		(legacy_teardrops no)
	)
	(paper "A4")
	(title_block
		(title "CM4 Baseboard")
		(date "2026-01-05")
		(rev "1.1.1")
		(company "Antmicro Ltd")
		(comment 1 "www.antmicro.com")
		(comment 9 "footprints 458-461 of 506")
	)
	(layers
		(0 "F.Cu" signal)
		(4 "In1.Cu" power)
		(6 "In2.Cu" power)
		(8 "In3.Cu" signal)
		(10 "In4.Cu" signal)
		(2 "B.Cu" signal)
		(9 "F.Adhes" user "F.Adhesive")
		(11 "B.Adhes" user "B.Adhesive")
		(13 "F.Paste" user)
		(15 "B.Paste" user)
		(5 "F.SilkS" user "F.Silkscreen")
		(7 "B.SilkS" user "B.Silkscreen")
		(1 "F.Mask" user)
		(3 "B.Mask" user)
		(17 "Dwgs.User" user "User.Drawings")
		(19 "Cmts.User" user "User.Comments")
		(21 "Eco1.User" user "User.Eco1")
		(23 "Eco2.User" user "User.Eco2")
		(25 "Edge.Cuts" user)
		(27 "Margin" user)
		(31 "F.CrtYd" user "F.Courtyard")
		(29 "B.CrtYd" user "B.Courtyard")
		(35 "F.Fab" user)
		(33 "B.Fab" user)
	)
	(footprint "antmicro-footprints:C_0402_1005Metric"
		(layer "B.Cu")
		(at 134.617962 148.4415 90)
		(descr "Capacitor SMD 0402")
		(tags "capacitor SMD 0402")
		(property "Reference" "C604"
			(at -3.745 0.18 90)
			(layer "B.SilkS")
			(effects
				(font
					(size 0.7 0.7)
					(thickness 0.15)
				)
				(justify right bottom mirror)
			)
		)
		(property "Value" "C_1u_0402"
			(at -1.022927 -2.155213 90)
			(layer "B.Fab")
			(effects
				(font
					(size 0.7 0.7)
					(thickness 0.15)
				)
				(justify right bottom mirror)
			)
		)
		(property "Datasheet" "https://product.tdk.com/en/search/capacitor/ceramic/mlcc/info?part_no=C1005X6S1A105K050BC"
			(at 0 0 90)
			(layer "B.Fab")
			(hide yes)
			(effects
				(font
					(size 1.27 1.27)
					(thickness 0.15)
				)
			)
		)
		(property "Manufacturer" "TDK"
			(at 0 0 90)
			(unlocked yes)
			(layer "B.Fab")
			(hide yes)
			(effects
				(font
					(size 1 1)
					(thickness 0.15)
				)
				(justify mirror)
			)
		)
		(property "MPN" "C1005X6S1A105K050BC"
			(at 0 0 90)
			(unlocked yes)
			(layer "B.Fab")
			(hide yes)
			(effects
				(font
					(size 1 1)
					(thickness 0.15)
				)
				(justify mirror)
			)
		)
		(property "Val" "1u"
			(at 0 0 90)
			(unlocked yes)
			(layer "B.Fab")
			(hide yes)
			(effects
				(font
					(size 1 1)
					(thickness 0.15)
				)
				(justify mirror)
			)
		)
		(property "License" "Apache-2.0"
			(at 0 0 90)
			(unlocked yes)
			(layer "B.Fab")
			(hide yes)
			(effects
				(font
					(size 1 1)
					(thickness 0.15)
				)
				(justify mirror)
			)
		)
		(property "Author" "Antmicro"
			(at 0 0 90)
			(unlocked yes)
			(layer "B.Fab")
			(hide yes)
			(effects
				(font
					(size 1 1)
					(thickness 0.15)
				)
				(justify mirror)
			)
		)
		(property "Voltage" ""
			(at 0 0 90)
			(unlocked yes)
			(layer "B.Fab")
			(hide yes)
			(effects
				(font
					(size 1 1)
					(thickness 0.15)
				)
				(justify mirror)
			)
		)
		(property "Dielectric" ""
			(at 0 0 90)
			(unlocked yes)
			(layer "B.Fab")
			(hide yes)
			(effects
				(font
					(size 1 1)
					(thickness 0.15)
				)
				(justify mirror)
			)
		)
		(sheetname "/CSI/")
		(sheetfile "csi.kicad_sch")
		(attr smd)
		(fp_rect
			(start -0.925 0.47)
			(end 0.925 -0.47)
			(stroke
				(width 0.05)
				(type default)
			)
			(fill no)
			(layer "B.CrtYd")
		)
		(fp_line
			(start 0.504 -0.248)
			(end -0.494 -0.248)
			(stroke
				(width 0.15)
				(type solid)
			)
			(layer "B.Fab")
		)
		(fp_line
			(start -0.494 -0.248)
			(end -0.494 0.25)
			(stroke
				(width 0.15)
				(type solid)
			)
			(layer "B.Fab")
		)
		(fp_line
			(start 0.504 0.25)
			(end 0.504 -0.248)
			(stroke
				(width 0.15)
				(type solid)
			)
			(layer "B.Fab")
		)
		(fp_line
			(start -0.494 0.25)
			(end 0.504 0.25)
			(stroke
				(width 0.15)
				(type solid)
			)
			(layer "B.Fab")
		)
		(fp_text user "License: Apache-2.0"
			(at -0.939 -5.799 270)
			(layer "B.Fab")
			(effects
				(font
					(size 0.7 0.7)
					(thickness 0.15)
				)
				(justify left bottom mirror)
			)
		)
		(fp_text user "Author: Antmicro"
			(at -0.939 -3.399 270)
			(layer "B.Fab")
			(effects
				(font
					(size 0.7 0.7)
					(thickness 0.15)
				)
				(justify left bottom mirror)
			)
		)
		(fp_text user "${REFERENCE}"
			(at -0.939 -4.599 270)
			(layer "B.Fab")
			(effects
				(font
					(size 0.7 0.7)
					(thickness 0.15)
				)
				(justify left bottom mirror)
			)
		)
		(pad "1" smd roundrect
			(at -0.48 0 90)
			(size 0.59 0.64)
			(layers "B.Cu" "B.Mask" "B.Paste")
			(roundrect_rratio 0.25)
			(net 3 "GND")
			(pintype "passive")
		)
		(pad "2" smd roundrect
			(at 0.48 0 90)
			(size 0.59 0.64)
			(layers "B.Cu" "B.Mask" "B.Paste")
			(roundrect_rratio 0.25)
			(net 20 "/CSI/CSI_5V")
			(pintype "passive")
		)
	)
	(footprint "antmicro-footprints:L_Bourns-SRP3212A"
		(layer "B.Cu")
		(at 90.667962 125.8165 -90)
		(property "Reference" "L901"
			(at -0.9 -2.46 90)
			(layer "B.SilkS")
			(effects
				(font
					(size 0.7 0.7)
					(thickness 0.15)
				)
				(justify left bottom mirror)
			)
		)
		(property "Value" "L_1u_5.5A_Bourns-SRP3212A"
			(at 0.05 -2.8 90)
			(layer "B.Fab")
			(effects
				(font
					(size 0.7 0.7)
					(thickness 0.15)
				)
				(justify left bottom mirror)
			)
		)
		(property "Datasheet" "https://www.mouser.com/datasheet/2/54/SRP3212A-3011944.pdf"
			(at 0 0 270)
			(layer "B.Fab")
			(hide yes)
			(effects
				(font
					(size 1.27 1.27)
					(thickness 0.15)
				)
			)
		)
		(property "Manufacturer" "Bourns"
			(at 0 0 270)
			(unlocked yes)
			(layer "B.Fab")
			(hide yes)
			(effects
				(font
					(size 1 1)
					(thickness 0.15)
				)
				(justify mirror)
			)
		)
		(property "MPN" "SRP3212A-1R0M"
			(at 0 0 270)
			(unlocked yes)
			(layer "B.Fab")
			(hide yes)
			(effects
				(font
					(size 1 1)
					(thickness 0.15)
				)
				(justify mirror)
			)
		)
		(property "Size" "3.2x2.5"
			(at 0 0 270)
			(unlocked yes)
			(layer "B.Fab")
			(hide yes)
			(effects
				(font
					(size 1 1)
					(thickness 0.15)
				)
				(justify mirror)
			)
		)
		(property "Val" "1u/5.5A"
			(at 0 0 270)
			(unlocked yes)
			(layer "B.Fab")
			(hide yes)
			(effects
				(font
					(size 1 1)
					(thickness 0.15)
				)
				(justify mirror)
			)
		)
		(property "Author" "Antmicro"
			(at 0 0 270)
			(unlocked yes)
			(layer "B.Fab")
			(hide yes)
			(effects
				(font
					(size 1 1)
					(thickness 0.15)
				)
				(justify mirror)
			)
		)
		(property "License" "Apache-2.0"
			(at 0 0 270)
			(unlocked yes)
			(layer "B.Fab")
			(hide yes)
			(effects
				(font
					(size 1 1)
					(thickness 0.15)
				)
				(justify mirror)
			)
		)
		(property "ISat" "6.5 A"
			(at 0 0 270)
			(unlocked yes)
			(layer "B.Fab")
			(hide yes)
			(effects
				(font
					(size 1 1)
					(thickness 0.15)
				)
				(justify mirror)
			)
		)
		(property "IMax" "5.5 A"
			(at 0 0 270)
			(unlocked yes)
			(layer "B.Fab")
			(hide yes)
			(effects
				(font
					(size 1 1)
					(thickness 0.15)
				)
				(justify mirror)
			)
		)
		(sheetname "/USB/")
		(sheetfile "usb.kicad_sch")
		(attr smd)
		(fp_line
			(start -0.4 1.25)
			(end 0.399 1.25)
			(stroke
				(width 0.15)
				(type solid)
			)
			(layer "B.SilkS")
		)
		(fp_line
			(start -0.4 -1.249)
			(end 0.399 -1.249)
			(stroke
				(width 0.15)
				(type solid)
			)
			(layer "B.SilkS")
		)
		(fp_rect
			(start -2.1 1.65)
			(end 2.1 -1.65)
			(stroke
				(width 0.05)
				(type solid)
			)
			(fill no)
			(layer "B.CrtYd")
		)
		(fp_rect
			(start -1.609 1.26)
			(end 1.609 -1.26)
			(stroke
				(width 0.15)
				(type solid)
			)
			(fill no)
			(layer "B.Fab")
		)
		(fp_text user "Author: Antmicro"
			(at -2.1 -6 90)
			(layer "B.Fab")
			(effects
				(font
					(size 0.7 0.7)
					(thickness 0.15)
				)
				(justify left bottom mirror)
			)
		)
		(fp_text user "License: Apache-2.0"
			(at -2.1 -7.2 90)
			(layer "B.Fab")
			(effects
				(font
					(size 0.7 0.7)
					(thickness 0.15)
				)
				(justify left bottom mirror)
			)
		)
		(fp_text user "${REFERENCE}"
			(at -2.1 -4.8 90)
			(layer "B.Fab")
			(effects
				(font
					(size 0.7 0.7)
					(thickness 0.15)
				)
				(justify left bottom mirror)
			)
		)
		(pad "1" smd roundrect
			(at -1.175 0 270)
			(size 1.35 2.8)
			(layers "B.Cu" "B.Mask" "B.Paste")
			(roundrect_rratio 0.1)
			(net 111 "/USB/SW_FTDI")
			(pintype "passive")
		)
		(pad "2" smd roundrect
			(at 1.175 0 270)
			(size 1.35 2.8)
			(layers "B.Cu" "B.Mask" "B.Paste")
			(roundrect_rratio 0.1)
			(net 113 "/USB/OUT_FTDI")
			(pintype "passive")
		)
	)
	(footprint "antmicro-footprints:XDFN-2_1x0.60mm"
		(layer "B.Cu")
		(at 98.492962 174.5415 90)
		(property "Reference" "D711"
			(at 1.595 6.465 90)
			(layer "B.SilkS")
			(effects
				(font
					(size 0.7 0.7)
					(thickness 0.15)
				)
				(justify left bottom mirror)
			)
		)
		(property "Value" "TPD1E0B04_XDFN-2"
			(at 0 -1.5 90)
			(layer "B.Fab")
			(effects
				(font
					(size 0.7 0.7)
					(thickness 0.15)
				)
				(justify right bottom mirror)
			)
		)
		(property "Datasheet" "https://www.ti.com/general/docs/suppproductinfo.tsp?distId=26&gotoUrl=https://www.ti.com/lit/gpn/tpd1e0b04"
			(at 0 0 90)
			(layer "B.Fab")
			(hide yes)
			(effects
				(font
					(size 1.27 1.27)
					(thickness 0.15)
				)
			)
		)
		(property "MPN" "TPD1E0B04DPYR"
			(at 273.034462 76.048538 0)
			(layer "B.Fab")
			(hide yes)
			(effects
				(font
					(size 1 1)
					(thickness 0.15)
				)
				(justify mirror)
			)
		)
		(property "Manufacturer" "Texas Instruments"
			(at 273.034462 76.048538 0)
			(layer "B.Fab")
			(hide yes)
			(effects
				(font
					(size 1 1)
					(thickness 0.15)
				)
				(justify mirror)
			)
		)
		(property "Author" "Antmicro"
			(at 0 0 90)
			(unlocked yes)
			(layer "B.Fab")
			(hide yes)
			(effects
				(font
					(size 1 1)
					(thickness 0.15)
				)
				(justify mirror)
			)
		)
		(property "License" "Apache-2.0"
			(at 0 0 90)
			(unlocked yes)
			(layer "B.Fab")
			(hide yes)
			(effects
				(font
					(size 1 1)
					(thickness 0.15)
				)
				(justify mirror)
			)
		)
		(sheetname "/Display/")
		(sheetfile "display.kicad_sch")
		(attr smd)
		(fp_rect
			(start -0.725 0.475)
			(end 0.725 -0.475)
			(stroke
				(width 0.05)
				(type solid)
			)
			(fill no)
			(layer "B.CrtYd")
		)
		(fp_rect
			(start -0.55 0.35)
			(end 0.55 -0.35)
			(stroke
				(width 0.15)
				(type solid)
			)
			(fill no)
			(layer "B.Fab")
		)
		(fp_text user "${REFERENCE}"
			(at -0.8 -3.2 270)
			(layer "B.Fab")
			(effects
				(font
					(size 0.7 0.7)
					(thickness 0.15)
				)
				(justify left bottom mirror)
			)
		)
		(fp_text user "License: Apache-2.0"
			(at -0.8 -5.6 270)
			(layer "B.Fab")
			(effects
				(font
					(size 0.7 0.7)
					(thickness 0.15)
				)
				(justify left bottom mirror)
			)
		)
		(fp_text user "Author: Antmicro"
			(at -0.8 -4.4 270)
			(layer "B.Fab")
			(effects
				(font
					(size 0.7 0.7)
					(thickness 0.15)
				)
				(justify left bottom mirror)
			)
		)
		(pad "1" smd roundrect
			(at -0.351 0 90)
			(size 0.3 0.5)
			(layers "B.Cu" "B.Mask" "B.Paste")
			(roundrect_rratio 0.25)
			(net 3 "GND")
			(pinfunction "C")
			(pintype "passive")
		)
		(pad "2" smd roundrect
			(at 0.349 0 90)
			(size 0.3 0.5)
			(layers "B.Cu" "B.Mask" "B.Paste")
			(roundrect_rratio 0.25)
			(net 9 "+3V3")
			(pinfunction "A")
			(pintype "passive")
		)
	)
	(footprint "antmicro-footprints:Mech_M2_2280_H2.5mm"
		(locked yes)
		(layer "B.Cu")
		(at 44.992962 124.767 -90)
		(property "Reference" "M501"
			(at 0.7495 -4.585 90)
			(layer "B.SilkS")
			(effects
				(font
					(size 0.7 0.7)
					(thickness 0.15)
				)
				(justify right bottom mirror)
			)
		)
		(property "Value" "Mech_M2_2280_H2.5mm"
			(at 0 -6.857 90)
			(layer "B.Fab")
			(effects
				(font
					(size 0.7 0.7)
					(thickness 0.15)
				)
				(justify right bottom mirror)
			)
		)
		(property "Description" "Mechanical model for M2 2280 2.5mm module"
			(at 0 0 90)
			(layer "B.Fab")
			(hide yes)
			(effects
				(font
					(size 1.27 1.27)
					(thickness 0.15)
				)
			)
		)
		(property "Manufacturer" ""
			(at 0 0 270)
			(unlocked yes)
			(layer "B.Fab")
			(hide yes)
			(effects
				(font
					(size 1 1)
					(thickness 0.15)
				)
				(justify mirror)
			)
		)
		(property "MPN" ""
			(at 0 0 270)
			(unlocked yes)
			(layer "B.Fab")
			(hide yes)
			(effects
				(font
					(size 1 1)
					(thickness 0.15)
				)
				(justify mirror)
			)
		)
		(property "Author" "Antmicro"
			(at 0 0 270)
			(unlocked yes)
			(layer "B.Fab")
			(hide yes)
			(effects
				(font
					(size 1 1)
					(thickness 0.15)
				)
				(justify mirror)
			)
		)
		(property "License" "Apache-2.0"
			(at 0 0 270)
			(unlocked yes)
			(layer "B.Fab")
			(hide yes)
			(effects
				(font
					(size 1 1)
					(thickness 0.15)
				)
				(justify mirror)
			)
		)
		(sheetname "/NVMe & microSD/")
		(sheetfile "nvme-micro-sd.kicad_sch")
		(attr exclude_from_pos_files exclude_from_bom allow_missing_courtyard dnp)
		(fp_rect
			(start -10.922 -0.0508)
			(end 11.0236 -80.0608)
			(stroke
				(width 0.15)
				(type solid)
			)
			(fill no)
			(layer "B.Fab")
		)
		(fp_text user "${REFERENCE}"
			(at -12.2428 -81.9912 90)
			(layer "B.Fab")
			(effects
				(font
					(size 0.7 0.7)
					(thickness 0.15)
				)
				(justify left bottom mirror)
			)
		)
		(fp_text user "Author: Antmicro"
			(at -12.2428 -83.1912 90)
			(layer "B.Fab")
			(effects
				(font
					(size 0.7 0.7)
					(thickness 0.15)
				)
				(justify left bottom mirror)
			)
		)
		(fp_text user "License: Apache-2.0"
			(at -12.2428 -84.3922 90)
			(layer "B.Fab")
			(effects
				(font
					(size 0.7 0.7)
					(thickness 0.15)
				)
				(justify left bottom mirror)
			)
		)
	)
)
